# S9S_MB_2U (Grand Teton) — schematic netlist excerpt (pin names and nets, part order shuffled) for the footprints in the layout excerpt that follows; sources: Cadence DE-HDL packaged netlist, KiCad conversion of 03242023_DA0F0TMBIJ0_F0T_Motherboard_J_brd_V01_OCP.brd

R672  Q_RES  0 5% CHIP  pkg 0402LF  page 230 : A = I3C_SPD_DDREFGH_CPU1_SCL ; B = I3C_SPD_DDREFGH_CPU1_R_SCL
C541  Q_CAP  1UF 25V 10% X6S  pkg C0402  page 133 : A = P3V3_AUX ; B = GND

(kicad_pcb
	(version 20260206)
	(generator "pcbnew")
	(generator_version "10.0")
	(general
		(thickness 1.6)
		(legacy_teardrops no)
	)
	(paper "A4")
	(title_block
		(title "03242023_DA0F0TMBIJ0_F0T_Motherboard_J_brd_V01_OCP.brd")
		(comment 1 "Grand Teton / footprints 4412-4413 of 6105")
	)
	(layers
		(0 "F.Cu" signal "TOP")
		(4 "In1.Cu" signal "GND")
		(6 "In2.Cu" signal "IN1")
		(8 "In3.Cu" signal "GND1")
		(10 "In4.Cu" signal "IN2")
		(12 "In5.Cu" signal "GND2")
		(14 "In6.Cu" signal "IN3")
		(16 "In7.Cu" signal "GND3")
		(18 "In8.Cu" signal "VCC")
		(20 "In9.Cu" signal "VCC1")
		(22 "In10.Cu" signal "GND4")
		(24 "In11.Cu" signal "IN4")
		(26 "In12.Cu" signal "GND5")
		(28 "In13.Cu" signal "IN5")
		(30 "In14.Cu" signal "GND6")
		(32 "In15.Cu" signal "IN6")
		(34 "In16.Cu" signal "GND7")
		(2 "B.Cu" signal "BOTTOM")
		(9 "F.Adhes" user "F.Adhesive")
		(11 "B.Adhes" user "B.Adhesive")
		(13 "F.Paste" user "Package Geometry/Pastemask Top")
		(15 "B.Paste" user "Package Geometry/Pastemask Bottom")
		(5 "F.SilkS" user "Ref Des/Silkscreen Top")
		(7 "B.SilkS" user "Ref Des/Silkscreen Bottom")
		(1 "F.Mask" user "Board Geometry/Soldermask Top")
		(3 "B.Mask" user "Board Geometry/Soldermask Bottom")
		(17 "Dwgs.User" user "User.Drawings")
		(19 "Cmts.User" user "User.Comments")
		(21 "Eco1.User" user "User.Eco1")
		(23 "Eco2.User" user "User.Eco2")
		(25 "Edge.Cuts" user "Board Geometry/Outline")
		(27 "Margin" user)
		(31 "F.CrtYd" user "Package Geometry/Place Bound Top")
		(29 "B.CrtYd" user "Package Geometry/Place Bound Bottom")
		(35 "F.Fab" user "Ref Des/Assembly Top")
		(33 "B.Fab" user "Ref Des/Assembly Bottom")
	)
	(footprint ""
		(layer "B.Cu")
		(at 204.133958 -192.95491)
		(property "Reference" "C541"
			(at 0 0 0)
			(layer "B.SilkS")
			(hide yes)
			(effects
				(font
					(size 1.27 1.27)
				)
				(justify mirror)
			)
		)
		(property "Value" ""
			(at 0 0 0)
			(layer "B.Fab")
			(effects
				(font
					(size 1.27 1.27)
				)
				(justify mirror)
			)
		)
		(duplicate_pad_numbers_are_jumpers no)
		(fp_line
			(start -0.7874 -0.4064)
			(end -0.7874 0.4064)
			(stroke
				(width 0.1524)
				(type default)
			)
			(layer "B.SilkS")
		)
		(fp_line
			(start -0.7874 0.4064)
			(end 0.7874 0.4064)
			(stroke
				(width 0.1524)
				(type default)
			)
			(layer "B.SilkS")
		)
		(fp_line
			(start 0.7874 -0.4064)
			(end -0.7874 -0.4064)
			(stroke
				(width 0.1524)
				(type default)
			)
			(layer "B.SilkS")
		)
		(fp_line
			(start 0.7874 0.4064)
			(end 0.7874 -0.4064)
			(stroke
				(width 0.1524)
				(type default)
			)
			(layer "B.SilkS")
		)
		(fp_line
			(start -0.67945 -0.3048)
			(end -0.67945 0.3048)
			(stroke
				(width 0.1)
				(type default)
			)
			(layer "B.Fab")
		)
		(fp_line
			(start -0.67945 0.3048)
			(end -0.120396 0.3048)
			(stroke
				(width 0.1)
				(type default)
			)
			(layer "B.Fab")
		)
		(fp_line
			(start -0.12065 -0.3048)
			(end -0.67945 -0.3048)
			(stroke
				(width 0.1)
				(type default)
			)
			(layer "B.Fab")
		)
		(fp_line
			(start -0.12065 -0.2794)
			(end -0.12065 -0.3048)
			(stroke
				(width 0.1)
				(type default)
			)
			(layer "B.Fab")
		)
		(fp_line
			(start -0.120396 0.2794)
			(end 0.12065 0.2794)
			(stroke
				(width 0.1)
				(type default)
			)
			(layer "B.Fab")
		)
		(fp_line
			(start -0.120396 0.3048)
			(end -0.120396 0.2794)
			(stroke
				(width 0.1)
				(type default)
			)
			(layer "B.Fab")
		)
		(fp_line
			(start 0.12065 -0.305054)
			(end 0.12065 -0.2794)
			(stroke
				(width 0.1)
				(type default)
			)
			(layer "B.Fab")
		)
		(fp_line
			(start 0.12065 -0.2794)
			(end -0.12065 -0.2794)
			(stroke
				(width 0.1)
				(type default)
			)
			(layer "B.Fab")
		)
		(fp_line
			(start 0.12065 0.2794)
			(end 0.12065 0.3048)
			(stroke
				(width 0.1)
				(type default)
			)
			(layer "B.Fab")
		)
		(fp_line
			(start 0.12065 0.3048)
			(end 0.67945 0.3048)
			(stroke
				(width 0.1)
				(type default)
			)
			(layer "B.Fab")
		)
		(fp_line
			(start 0.67945 -0.305054)
			(end 0.12065 -0.305054)
			(stroke
				(width 0.1)
				(type default)
			)
			(layer "B.Fab")
		)
		(fp_line
			(start 0.67945 0.3048)
			(end 0.67945 -0.305054)
			(stroke
				(width 0.1)
				(type default)
			)
			(layer "B.Fab")
		)
		(pad "1" smd circle
			(at 0.40005 0 180)
			(size 0 0)
			(layers "B.Cu" "B.Mask" "B.Paste")
			(net "P3V3_AUX")
		)
		(pad "2" smd circle
			(at -0.40005 0 180)
			(size 0 0)
			(layers "B.Cu" "B.Mask" "B.Paste")
			(net "GND")
		)
	)
	(footprint ""
		(layer "B.Cu")
		(at 150.387304 -190.36411 90)
		(property "Reference" "R672"
			(at 0 0 90)
			(layer "B.SilkS")
			(hide yes)
			(effects
				(font
					(size 1.27 1.27)
				)
				(justify mirror)
			)
		)
		(property "Value" ""
			(at 0 0 90)
			(layer "B.Fab")
			(effects
				(font
					(size 1.27 1.27)
				)
				(justify mirror)
			)
		)
		(duplicate_pad_numbers_are_jumpers no)
		(fp_line
			(start 0.7874 -0.4064)
			(end -0.7874 -0.4064)
			(stroke
				(width 0.1524)
				(type default)
			)
			(layer "B.SilkS")
		)
		(fp_line
			(start -0.7874 -0.4064)
			(end -0.7874 0.4064)
			(stroke
				(width 0.1524)
				(type default)
			)
			(layer "B.SilkS")
		)
		(fp_line
			(start 0.7874 0.4064)
			(end 0.7874 -0.4064)
			(stroke
				(width 0.1524)
				(type default)
			)
			(layer "B.SilkS")
		)
		(fp_line
			(start -0.7874 0.4064)
			(end 0.7874 0.4064)
			(stroke
				(width 0.1524)
				(type default)
			)
			(layer "B.SilkS")
		)
		(fp_line
			(start 0.67945 -0.305054)
			(end 0.12065 -0.305054)
			(stroke
				(width 0.1)
				(type default)
			)
			(layer "B.Fab")
		)
		(fp_line
			(start 0.12065 -0.305054)
			(end 0.12065 -0.2794)
			(stroke
				(width 0.1)
				(type default)
			)
			(layer "B.Fab")
		)
		(fp_line
			(start -0.12065 -0.3048)
			(end -0.67945 -0.3048)
			(stroke
				(width 0.1)
				(type default)
			)
			(layer "B.Fab")
		)
		(fp_line
			(start -0.67945 -0.3048)
			(end -0.67945 0.3048)
			(stroke
				(width 0.1)
				(type default)
			)
			(layer "B.Fab")
		)
		(fp_line
			(start 0.12065 -0.2794)
			(end -0.12065 -0.2794)
			(stroke
				(width 0.1)
				(type default)
			)
			(layer "B.Fab")
		)
		(fp_line
			(start -0.12065 -0.2794)
			(end -0.12065 -0.3048)
			(stroke
				(width 0.1)
				(type default)
			)
			(layer "B.Fab")
		)
		(fp_line
			(start 0.12065 0.2794)
			(end 0.12065 0.3048)
			(stroke
				(width 0.1)
				(type default)
			)
			(layer "B.Fab")
		)
		(fp_line
			(start -0.120396 0.2794)
			(end 0.12065 0.2794)
			(stroke
				(width 0.1)
				(type default)
			)
			(layer "B.Fab")
		)
		(fp_line
			(start 0.67945 0.3048)
			(end 0.67945 -0.305054)
			(stroke
				(width 0.1)
				(type default)
			)
			(layer "B.Fab")
		)
		(fp_line
			(start 0.12065 0.3048)
			(end 0.67945 0.3048)
			(stroke
				(width 0.1)
				(type default)
			)
			(layer "B.Fab")
		)
		(fp_line
			(start -0.120396 0.3048)
			(end -0.120396 0.2794)
			(stroke
				(width 0.1)
				(type default)
			)
			(layer "B.Fab")
		)
		(fp_line
			(start -0.67945 0.3048)
			(end -0.120396 0.3048)
			(stroke
				(width 0.1)
				(type default)
			)
			(layer "B.Fab")
		)
		(pad "1" smd circle
			(at 0.40005 0 270)
			(size 0 0)
			(layers "B.Cu" "B.Mask" "B.Paste")
			(net "I3C_SPD_DDREFGH_CPU1_SCL")
		)
		(pad "2" smd circle
			(at -0.40005 0 270)
			(size 0 0)
			(layers "B.Cu" "B.Mask" "B.Paste")
			(net "I3C_SPD_DDREFGH_CPU1_R_SCL")
		)
	)
)
